# T6G (Grand Teton) — schematic netlist excerpt (pin names and nets, part order shuffled) for the footprints in the layout excerpt that follows; sources: Cadence DE-HDL packaged netlist, KiCad conversion of 04192023_DAF0TMB3IC0_F0TG_MB_C_brd_V02_OCP.brd

R338  Q_RES  0 5% CHIP  pkg 0402LF  page 161 : A = SMB_APML_CPU1_MUX2_SDA ; B = SMB_APML_CPU1_SDA
PR6000  Q_RES  0 5% CHIP  pkg 0402LF  page 192 : A = GND ; B = PVDD_33_S5_MODE

(kicad_pcb
	(version 20260206)
	(generator "pcbnew")
	(generator_version "10.0")
	(general
		(thickness 1.6)
		(legacy_teardrops no)
	)
	(paper "A4")
	(title_block
		(title "04192023_DAF0TMB3IC0_F0TG_MB_C_brd_V02_OCP.brd")
		(comment 1 "Grand Teton / footprints 7152-7153 of 8354")
	)
	(layers
		(0 "F.Cu" signal "TOP")
		(4 "In1.Cu" signal "GND")
		(6 "In2.Cu" signal "IN1")
		(8 "In3.Cu" signal "GND1")
		(10 "In4.Cu" signal "IN2")
		(12 "In5.Cu" signal "GND2")
		(14 "In6.Cu" signal "IN3")
		(16 "In7.Cu" signal "GND3")
		(18 "In8.Cu" signal "VCC")
		(20 "In9.Cu" signal "VCC1")
		(22 "In10.Cu" signal "GND4")
		(24 "In11.Cu" signal "IN4")
		(26 "In12.Cu" signal "GND5")
		(28 "In13.Cu" signal "IN5")
		(30 "In14.Cu" signal "GND6")
		(32 "In15.Cu" signal "IN6")
		(34 "In16.Cu" signal "GND7")
		(2 "B.Cu" signal "BOTTOM")
		(9 "F.Adhes" user "F.Adhesive")
		(11 "B.Adhes" user "B.Adhesive")
		(13 "F.Paste" user "Package Geometry/Pastemask Top")
		(15 "B.Paste" user "Package Geometry/Pastemask Bottom")
		(5 "F.SilkS" user "Ref Des/Silkscreen Top")
		(7 "B.SilkS" user "Ref Des/Silkscreen Bottom")
		(1 "F.Mask" user "Board Geometry/Soldermask Top")
		(3 "B.Mask" user "Board Geometry/Soldermask Bottom")
		(17 "Dwgs.User" user "User.Drawings")
		(19 "Cmts.User" user "User.Comments")
		(21 "Eco1.User" user "User.Eco1")
		(23 "Eco2.User" user "User.Eco2")
		(25 "Edge.Cuts" user "Board Geometry/Outline")
		(27 "Margin" user)
		(31 "F.CrtYd" user "Package Geometry/Place Bound Top")
		(29 "B.CrtYd" user "Package Geometry/Place Bound Bottom")
		(35 "F.Fab" user "Ref Des/Assembly Top")
		(33 "B.Fab" user "Ref Des/Assembly Bottom")
	)
	(footprint ""
		(layer "B.Cu")
		(at 203.897484 -341.853012 180)
		(property "Reference" "PR6000"
			(at 0 0 0)
			(layer "B.SilkS")
			(hide yes)
			(effects
				(font
					(size 1.27 1.27)
				)
				(justify mirror)
			)
		)
		(property "Value" ""
			(at 0 0 0)
			(layer "B.Fab")
			(effects
				(font
					(size 1.27 1.27)
				)
				(justify mirror)
			)
		)
		(duplicate_pad_numbers_are_jumpers no)
		(fp_line
			(start 0.7874 0.4064)
			(end 0.7874 -0.4064)
			(stroke
				(width 0.1524)
				(type default)
			)
			(layer "B.SilkS")
		)
		(fp_line
			(start 0.7874 -0.4064)
			(end -0.7874 -0.4064)
			(stroke
				(width 0.1524)
				(type default)
			)
			(layer "B.SilkS")
		)
		(fp_line
			(start -0.7874 0.4064)
			(end 0.7874 0.4064)
			(stroke
				(width 0.1524)
				(type default)
			)
			(layer "B.SilkS")
		)
		(fp_line
			(start -0.7874 -0.4064)
			(end -0.7874 0.4064)
			(stroke
				(width 0.1524)
				(type default)
			)
			(layer "B.SilkS")
		)
		(fp_line
			(start 0.67945 0.3048)
			(end 0.67945 -0.305054)
			(stroke
				(width 0.1)
				(type default)
			)
			(layer "B.Fab")
		)
		(fp_line
			(start 0.67945 -0.305054)
			(end 0.12065 -0.305054)
			(stroke
				(width 0.1)
				(type default)
			)
			(layer "B.Fab")
		)
		(fp_line
			(start 0.12065 0.3048)
			(end 0.67945 0.3048)
			(stroke
				(width 0.1)
				(type default)
			)
			(layer "B.Fab")
		)
		(fp_line
			(start 0.12065 0.2794)
			(end 0.12065 0.3048)
			(stroke
				(width 0.1)
				(type default)
			)
			(layer "B.Fab")
		)
		(fp_line
			(start 0.12065 -0.2794)
			(end -0.12065 -0.2794)
			(stroke
				(width 0.1)
				(type default)
			)
			(layer "B.Fab")
		)
		(fp_line
			(start 0.12065 -0.305054)
			(end 0.12065 -0.2794)
			(stroke
				(width 0.1)
				(type default)
			)
			(layer "B.Fab")
		)
		(fp_line
			(start -0.120396 0.3048)
			(end -0.120396 0.2794)
			(stroke
				(width 0.1)
				(type default)
			)
			(layer "B.Fab")
		)
		(fp_line
			(start -0.120396 0.2794)
			(end 0.12065 0.2794)
			(stroke
				(width 0.1)
				(type default)
			)
			(layer "B.Fab")
		)
		(fp_line
			(start -0.12065 -0.2794)
			(end -0.12065 -0.3048)
			(stroke
				(width 0.1)
				(type default)
			)
			(layer "B.Fab")
		)
		(fp_line
			(start -0.12065 -0.3048)
			(end -0.67945 -0.3048)
			(stroke
				(width 0.1)
				(type default)
			)
			(layer "B.Fab")
		)
		(fp_line
			(start -0.67945 0.3048)
			(end -0.120396 0.3048)
			(stroke
				(width 0.1)
				(type default)
			)
			(layer "B.Fab")
		)
		(fp_line
			(start -0.67945 -0.3048)
			(end -0.67945 0.3048)
			(stroke
				(width 0.1)
				(type default)
			)
			(layer "B.Fab")
		)
		(pad "1" smd circle
			(at 0.40005 0)
			(size 0 0)
			(layers "B.Cu" "B.Mask" "B.Paste")
			(net "GND")
		)
		(pad "2" smd circle
			(at -0.40005 0)
			(size 0 0)
			(layers "B.Cu" "B.Mask" "B.Paste")
			(net "PVDD_33_S5_MODE")
		)
	)
	(footprint ""
		(layer "B.Cu")
		(at 234.569 -241.2111 90)
		(property "Reference" "R338"
			(at 0 0 90)
			(layer "B.SilkS")
			(hide yes)
			(effects
				(font
					(size 1.27 1.27)
				)
				(justify mirror)
			)
		)
		(property "Value" ""
			(at 0 0 90)
			(layer "B.Fab")
			(effects
				(font
					(size 1.27 1.27)
				)
				(justify mirror)
			)
		)
		(duplicate_pad_numbers_are_jumpers no)
		(fp_line
			(start 0.7874 -0.4064)
			(end -0.7874 -0.4064)
			(stroke
				(width 0.1524)
				(type default)
			)
			(layer "B.SilkS")
		)
		(fp_line
			(start -0.7874 -0.4064)
			(end -0.7874 0.4064)
			(stroke
				(width 0.1524)
				(type default)
			)
			(layer "B.SilkS")
		)
		(fp_line
			(start 0.7874 0.4064)
			(end 0.7874 -0.4064)
			(stroke
				(width 0.1524)
				(type default)
			)
			(layer "B.SilkS")
		)
		(fp_line
			(start -0.7874 0.4064)
			(end 0.7874 0.4064)
			(stroke
				(width 0.1524)
				(type default)
			)
			(layer "B.SilkS")
		)
		(fp_line
			(start 0.67945 -0.305054)
			(end 0.12065 -0.305054)
			(stroke
				(width 0.1)
				(type default)
			)
			(layer "B.Fab")
		)
		(fp_line
			(start 0.12065 -0.305054)
			(end 0.12065 -0.2794)
			(stroke
				(width 0.1)
				(type default)
			)
			(layer "B.Fab")
		)
		(fp_line
			(start -0.12065 -0.3048)
			(end -0.67945 -0.3048)
			(stroke
				(width 0.1)
				(type default)
			)
			(layer "B.Fab")
		)
		(fp_line
			(start -0.67945 -0.3048)
			(end -0.67945 0.3048)
			(stroke
				(width 0.1)
				(type default)
			)
			(layer "B.Fab")
		)
		(fp_line
			(start 0.12065 -0.2794)
			(end -0.12065 -0.2794)
			(stroke
				(width 0.1)
				(type default)
			)
			(layer "B.Fab")
		)
		(fp_line
			(start -0.12065 -0.2794)
			(end -0.12065 -0.3048)
			(stroke
				(width 0.1)
				(type default)
			)
			(layer "B.Fab")
		)
		(fp_line
			(start 0.12065 0.2794)
			(end 0.12065 0.3048)
			(stroke
				(width 0.1)
				(type default)
			)
			(layer "B.Fab")
		)
		(fp_line
			(start -0.120396 0.2794)
			(end 0.12065 0.2794)
			(stroke
				(width 0.1)
				(type default)
			)
			(layer "B.Fab")
		)
		(fp_line
			(start 0.67945 0.3048)
			(end 0.67945 -0.305054)
			(stroke
				(width 0.1)
				(type default)
			)
			(layer "B.Fab")
		)
		(fp_line
			(start 0.12065 0.3048)
			(end 0.67945 0.3048)
			(stroke
				(width 0.1)
				(type default)
			)
			(layer "B.Fab")
		)
		(fp_line
			(start -0.120396 0.3048)
			(end -0.120396 0.2794)
			(stroke
				(width 0.1)
				(type default)
			)
			(layer "B.Fab")
		)
		(fp_line
			(start -0.67945 0.3048)
			(end -0.120396 0.3048)
			(stroke
				(width 0.1)
				(type default)
			)
			(layer "B.Fab")
		)
		(pad "1" smd rect
			(at 0.40005 0 90)
			(size 0.4572 0.508)
			(layers "B.Cu" "B.Mask" "B.Paste")
			(net "SMB_APML_CPU1_MUX2_SDA")
		)
		(pad "2" smd rect
			(at -0.40005 0 90)
			(size 0.4572 0.508)
			(layers "B.Cu" "B.Mask" "B.Paste")
			(net "SMB_APML_CPU1_SDA")
		)
	)
)
